(kicad_pcb
	(version 20260206)
	(generator "pcbnew")
	(generator_version "10.0")
	(general
		(thickness 1.6)
		(legacy_teardrops no)
	)
	(paper "A4")
	(title_block
		(title "01162023_DA0F0TEBIF0_F0T_Expander_BD_F_brd_V02_OCP.brd")
		(comment 1 "Grand Teton / footprints 8957-8965 of 9728")
	)
	(layers
		(0 "F.Cu" signal "TOP")
		(4 "In1.Cu" signal "GND")
		(6 "In2.Cu" signal "VCC")
		(8 "In3.Cu" signal "VCC1")
		(10 "In4.Cu" signal "GND1")
		(12 "In5.Cu" signal "IN1")
		(14 "In6.Cu" signal "GND2")
		(16 "In7.Cu" signal "IN2")
		(18 "In8.Cu" signal "GND3")
		(20 "In9.Cu" signal "IN3")
		(22 "In10.Cu" signal "GND4")
		(24 "In11.Cu" signal "IN4")
		(26 "In12.Cu" signal "GND5")
		(28 "In13.Cu" signal "IN5")
		(30 "In14.Cu" signal "GND6")
		(32 "In15.Cu" signal "IN6")
		(34 "In16.Cu" signal "GND7")
		(2 "B.Cu" signal "BOTTOM")
		(9 "F.Adhes" user "F.Adhesive")
		(11 "B.Adhes" user "B.Adhesive")
		(13 "F.Paste" user "Package Geometry/Pastemask Top")
		(15 "B.Paste" user "Package Geometry/Pastemask Bottom")
		(5 "F.SilkS" user "Ref Des/Silkscreen Top")
		(7 "B.SilkS" user "Ref Des/Silkscreen Bottom")
		(1 "F.Mask" user "Board Geometry/Soldermask Top")
		(3 "B.Mask" user "Board Geometry/Soldermask Bottom")
		(17 "Dwgs.User" user "User.Drawings")
		(19 "Cmts.User" user "User.Comments")
		(21 "Eco1.User" user "User.Eco1")
		(23 "Eco2.User" user "User.Eco2")
		(25 "Edge.Cuts" user "Board Geometry/Outline")
		(27 "Margin" user)
		(31 "F.CrtYd" user "Package Geometry/Place Bound Top")
		(29 "B.CrtYd" user "Package Geometry/Place Bound Bottom")
		(35 "F.Fab" user "Ref Des/Assembly Top")
		(33 "B.Fab" user "Ref Des/Assembly Bottom")
	)
	(footprint ""
		(layer "B.Cu")
		(at 289.94989 -303.499774 -90)
		(property "Reference" "C3265"
			(at 0 0 90)
			(layer "B.SilkS")
			(hide yes)
			(effects
				(font
					(size 1.27 1.27)
				)
				(justify mirror)
			)
		)
		(property "Value" ""
			(at 0 0 90)
			(layer "B.Fab")
			(effects
				(font
					(size 1.27 1.27)
				)
				(justify mirror)
			)
		)
		(duplicate_pad_numbers_are_jumpers no)
		(fp_line
			(start -0.299974 0.150114)
			(end 0.299974 0.150114)
			(stroke
				(width 0.1)
				(type default)
			)
			(layer "B.Fab")
		)
		(fp_line
			(start 0.299974 0.150114)
			(end 0.299974 -0.150114)
			(stroke
				(width 0.1)
				(type default)
			)
			(layer "B.Fab")
		)
		(fp_line
			(start -0.299974 -0.150114)
			(end -0.299974 0.150114)
			(stroke
				(width 0.1)
				(type default)
			)
			(layer "B.Fab")
		)
		(fp_line
			(start 0.299974 -0.150114)
			(end -0.299974 -0.150114)
			(stroke
				(width 0.1)
				(type default)
			)
			(layer "B.Fab")
		)
		(pad "1" smd rect
			(at 0.2667 0 90)
			(size 0.3048 0.381)
			(layers "B.Cu" "B.Mask" "B.Paste")
			(net "P1V25_PEX2")
		)
		(pad "2" smd rect
			(at -0.2667 0 90)
			(size 0.3048 0.381)
			(layers "B.Cu" "B.Mask" "B.Paste")
			(net "GND")
		)
	)
	(footprint ""
		(layer "B.Cu")
		(at 176.699926 -301.599854 -90)
		(property "Reference" "C1454"
			(at 0 0 90)
			(layer "B.SilkS")
			(hide yes)
			(effects
				(font
					(size 1.27 1.27)
				)
				(justify mirror)
			)
		)
		(property "Value" ""
			(at 0 0 90)
			(layer "B.Fab")
			(effects
				(font
					(size 1.27 1.27)
				)
				(justify mirror)
			)
		)
		(duplicate_pad_numbers_are_jumpers no)
		(fp_line
			(start -0.299974 0.150114)
			(end 0.299974 0.150114)
			(stroke
				(width 0.1)
				(type default)
			)
			(layer "B.Fab")
		)
		(fp_line
			(start 0.299974 0.150114)
			(end 0.299974 -0.150114)
			(stroke
				(width 0.1)
				(type default)
			)
			(layer "B.Fab")
		)
		(fp_line
			(start -0.299974 -0.150114)
			(end -0.299974 0.150114)
			(stroke
				(width 0.1)
				(type default)
			)
			(layer "B.Fab")
		)
		(fp_line
			(start 0.299974 -0.150114)
			(end -0.299974 -0.150114)
			(stroke
				(width 0.1)
				(type default)
			)
			(layer "B.Fab")
		)
		(pad "1" smd rect
			(at 0.2667 0 90)
			(size 0.3048 0.381)
			(layers "B.Cu" "B.Mask" "B.Paste")
			(net "P0V8_SERDES_VDDA_PEX1")
		)
		(pad "2" smd rect
			(at -0.2667 0 90)
			(size 0.3048 0.381)
			(layers "B.Cu" "B.Mask" "B.Paste")
			(net "GND")
		)
	)
	(footprint ""
		(layer "B.Cu")
		(at 338.76615 -84.500974 -90)
		(property "Reference" "C2676"
			(at 0 0 90)
			(layer "B.SilkS")
			(hide yes)
			(effects
				(font
					(size 1.27 1.27)
				)
				(justify mirror)
			)
		)
		(property "Value" ""
			(at 0 0 90)
			(layer "B.Fab")
			(effects
				(font
					(size 1.27 1.27)
				)
				(justify mirror)
			)
		)
		(duplicate_pad_numbers_are_jumpers no)
		(fp_line
			(start -0.7874 0.4064)
			(end 0.7874 0.4064)
			(stroke
				(width 0.1524)
				(type default)
			)
			(layer "B.SilkS")
		)
		(fp_line
			(start 0.7874 0.4064)
			(end 0.7874 -0.4064)
			(stroke
				(width 0.1524)
				(type default)
			)
			(layer "B.SilkS")
		)
		(fp_line
			(start -0.7874 -0.4064)
			(end -0.7874 0.4064)
			(stroke
				(width 0.1524)
				(type default)
			)
			(layer "B.SilkS")
		)
		(fp_line
			(start 0.7874 -0.4064)
			(end -0.7874 -0.4064)
			(stroke
				(width 0.1524)
				(type default)
			)
			(layer "B.SilkS")
		)
		(fp_line
			(start -0.67945 0.3048)
			(end -0.120396 0.3048)
			(stroke
				(width 0.1)
				(type default)
			)
			(layer "B.Fab")
		)
		(fp_line
			(start -0.120396 0.3048)
			(end -0.120396 0.2794)
			(stroke
				(width 0.1)
				(type default)
			)
			(layer "B.Fab")
		)
		(fp_line
			(start 0.12065 0.3048)
			(end 0.67945 0.3048)
			(stroke
				(width 0.1)
				(type default)
			)
			(layer "B.Fab")
		)
		(fp_line
			(start 0.67945 0.3048)
			(end 0.67945 -0.305054)
			(stroke
				(width 0.1)
				(type default)
			)
			(layer "B.Fab")
		)
		(fp_line
			(start -0.120396 0.2794)
			(end 0.12065 0.2794)
			(stroke
				(width 0.1)
				(type default)
			)
			(layer "B.Fab")
		)
		(fp_line
			(start 0.12065 0.2794)
			(end 0.12065 0.3048)
			(stroke
				(width 0.1)
				(type default)
			)
			(layer "B.Fab")
		)
		(fp_line
			(start -0.12065 -0.2794)
			(end -0.12065 -0.3048)
			(stroke
				(width 0.1)
				(type default)
			)
			(layer "B.Fab")
		)
		(fp_line
			(start 0.12065 -0.2794)
			(end -0.12065 -0.2794)
			(stroke
				(width 0.1)
				(type default)
			)
			(layer "B.Fab")
		)
		(fp_line
			(start -0.67945 -0.3048)
			(end -0.67945 0.3048)
			(stroke
				(width 0.1)
				(type default)
			)
			(layer "B.Fab")
		)
		(fp_line
			(start -0.12065 -0.3048)
			(end -0.67945 -0.3048)
			(stroke
				(width 0.1)
				(type default)
			)
			(layer "B.Fab")
		)
		(fp_line
			(start 0.12065 -0.305054)
			(end 0.12065 -0.2794)
			(stroke
				(width 0.1)
				(type default)
			)
			(layer "B.Fab")
		)
		(fp_line
			(start 0.67945 -0.305054)
			(end 0.12065 -0.305054)
			(stroke
				(width 0.1)
				(type default)
			)
			(layer "B.Fab")
		)
		(pad "1" smd circle
			(at 0.40005 0 90)
			(size 0 0)
			(layers "B.Cu" "B.Mask" "B.Paste")
			(net "P3V3_VDD_9ZXL0851_8_15")
		)
		(pad "2" smd circle
			(at -0.40005 0 90)
			(size 0 0)
			(layers "B.Cu" "B.Mask" "B.Paste")
			(net "GND")
		)
	)
	(footprint ""
		(layer "B.Cu")
		(at 377.587002 -221.066106)
		(property "Reference" "R926"
			(at 0 0 0)
			(layer "B.SilkS")
			(hide yes)
			(effects
				(font
					(size 1.27 1.27)
				)
				(justify mirror)
			)
		)
		(property "Value" ""
			(at 0 0 0)
			(layer "B.Fab")
			(effects
				(font
					(size 1.27 1.27)
				)
				(justify mirror)
			)
		)
		(duplicate_pad_numbers_are_jumpers no)
		(fp_line
			(start -0.7874 -0.4064)
			(end -0.7874 0.4064)
			(stroke
				(width 0.1524)
				(type default)
			)
			(layer "B.SilkS")
		)
		(fp_line
			(start -0.7874 0.4064)
			(end 0.7874 0.4064)
			(stroke
				(width 0.1524)
				(type default)
			)
			(layer "B.SilkS")
		)
		(fp_line
			(start 0.7874 -0.4064)
			(end -0.7874 -0.4064)
			(stroke
				(width 0.1524)
				(type default)
			)
			(layer "B.SilkS")
		)
		(fp_line
			(start 0.7874 0.4064)
			(end 0.7874 -0.4064)
			(stroke
				(width 0.1524)
				(type default)
			)
			(layer "B.SilkS")
		)
		(fp_line
			(start -0.67945 -0.3048)
			(end -0.67945 0.3048)
			(stroke
				(width 0.1)
				(type default)
			)
			(layer "B.Fab")
		)
		(fp_line
			(start -0.67945 0.3048)
			(end -0.120396 0.3048)
			(stroke
				(width 0.1)
				(type default)
			)
			(layer "B.Fab")
		)
		(fp_line
			(start -0.12065 -0.3048)
			(end -0.67945 -0.3048)
			(stroke
				(width 0.1)
				(type default)
			)
			(layer "B.Fab")
		)
		(fp_line
			(start -0.12065 -0.2794)
			(end -0.12065 -0.3048)
			(stroke
				(width 0.1)
				(type default)
			)
			(layer "B.Fab")
		)
		(fp_line
			(start -0.120396 0.2794)
			(end 0.12065 0.2794)
			(stroke
				(width 0.1)
				(type default)
			)
			(layer "B.Fab")
		)
		(fp_line
			(start -0.120396 0.3048)
			(end -0.120396 0.2794)
			(stroke
				(width 0.1)
				(type default)
			)
			(layer "B.Fab")
		)
		(fp_line
			(start 0.12065 -0.305054)
			(end 0.12065 -0.2794)
			(stroke
				(width 0.1)
				(type default)
			)
			(layer "B.Fab")
		)
		(fp_line
			(start 0.12065 -0.2794)
			(end -0.12065 -0.2794)
			(stroke
				(width 0.1)
				(type default)
			)
			(layer "B.Fab")
		)
		(fp_line
			(start 0.12065 0.2794)
			(end 0.12065 0.3048)
			(stroke
				(width 0.1)
				(type default)
			)
			(layer "B.Fab")
		)
		(fp_line
			(start 0.12065 0.3048)
			(end 0.67945 0.3048)
			(stroke
				(width 0.1)
				(type default)
			)
			(layer "B.Fab")
		)
		(fp_line
			(start 0.67945 -0.305054)
			(end 0.12065 -0.305054)
			(stroke
				(width 0.1)
				(type default)
			)
			(layer "B.Fab")
		)
		(fp_line
			(start 0.67945 0.3048)
			(end 0.67945 -0.305054)
			(stroke
				(width 0.1)
				(type default)
			)
			(layer "B.Fab")
		)
		(pad "1" smd circle
			(at 0.40005 0 180)
			(size 0 0)
			(layers "B.Cu" "B.Mask" "B.Paste")
			(net "UART_PEX1_SDB_BUF_RX")
		)
		(pad "2" smd circle
			(at -0.40005 0 180)
			(size 0 0)
			(layers "B.Cu" "B.Mask" "B.Paste")
			(net "P1V8_PEX")
		)
	)
	(footprint ""
		(layer "B.Cu")
		(at 73.400158 -112.604296)
		(property "Reference" "C863"
			(at 0 0 0)
			(layer "B.SilkS")
			(hide yes)
			(effects
				(font
					(size 1.27 1.27)
				)
				(justify mirror)
			)
		)
		(property "Value" ""
			(at 0 0 0)
			(layer "B.Fab")
			(effects
				(font
					(size 1.27 1.27)
				)
				(justify mirror)
			)
		)
		(duplicate_pad_numbers_are_jumpers no)
		(fp_line
			(start -0.299974 -0.150114)
			(end -0.299974 0.150114)
			(stroke
				(width 0.1)
				(type default)
			)
			(layer "B.Fab")
		)
		(fp_line
			(start -0.299974 0.150114)
			(end 0.299974 0.150114)
			(stroke
				(width 0.1)
				(type default)
			)
			(layer "B.Fab")
		)
		(fp_line
			(start 0.299974 -0.150114)
			(end -0.299974 -0.150114)
			(stroke
				(width 0.1)
				(type default)
			)
			(layer "B.Fab")
		)
		(fp_line
			(start 0.299974 0.150114)
			(end 0.299974 -0.150114)
			(stroke
				(width 0.1)
				(type default)
			)
			(layer "B.Fab")
		)
		(pad "1" smd rect
			(at 0.2667 0 180)
			(size 0.3048 0.381)
			(layers "B.Cu" "B.Mask" "B.Paste")
			(net "P12V_NIC1")
		)
		(pad "2" smd rect
			(at -0.2667 0 180)
			(size 0.3048 0.381)
			(layers "B.Cu" "B.Mask" "B.Paste")
			(net "GND")
		)
	)
	(footprint ""
		(layer "B.Cu")
		(at 151.209248 -444.912496 180)
		(property "Reference" "X56"
			(at -4.769104 2.281428 90)
			(unlocked yes)
			(layer "B.SilkS")
			(effects
				(font
					(size 0.7874 0.5842)
					(thickness 0.1524)
				)
				(justify left mirror)
			)
		)
		(property "Value" ""
			(at 0 0 0)
			(layer "B.Fab")
			(effects
				(font
					(size 1.27 1.27)
				)
				(justify mirror)
			)
		)
		(property "Device Type" "TP_TDR_4P_FTS_MPKT4_H025P0200_IO_TP15_TP_TDR_4P_DIP"
			(at -1.30175 1.27 90)
			(unlocked yes)
			(layer "B.Fab")
			(hide yes)
			(effects
				(font
					(size 0.635 0.4064)
					(thickness 0.1524)
				)
				(justify mirror)
			)
		)
		(property "User Part Number" "TP15"
			(at -1.30175 1.27 90)
			(unlocked yes)
			(layer "Cmts.User")
			(hide yes)
			(effects
				(font
					(size 0.635 0.4064)
					(thickness 0.1524)
				)
				(justify mirror)
			)
		)
		(duplicate_pad_numbers_are_jumpers no)
		(fp_line
			(start 0 3.81)
			(end -2.54 3.81)
			(stroke
				(width 0.1524)
				(type default)
			)
			(layer "B.SilkS")
		)
		(fp_line
			(start 0 3.175)
			(end 0 3.81)
			(stroke
				(width 0.1524)
				(type default)
			)
			(layer "B.SilkS")
		)
		(fp_line
			(start 0 0.635)
			(end 0 1.905)
			(stroke
				(width 0.1524)
				(type default)
			)
			(layer "B.SilkS")
		)
		(fp_line
			(start 0 -1.27)
			(end 0 -0.635)
			(stroke
				(width 0.1524)
				(type default)
			)
			(layer "B.SilkS")
		)
		(fp_line
			(start -2.54 3.81)
			(end -2.54 3.6703)
			(stroke
				(width 0.1524)
				(type default)
			)
			(layer "B.SilkS")
		)
		(fp_line
			(start -2.54 1.4097)
			(end -2.54 1.1303)
			(stroke
				(width 0.1524)
				(type default)
			)
			(layer "B.SilkS")
		)
		(fp_line
			(start -2.54 -1.1303)
			(end -2.54 -1.27)
			(stroke
				(width 0.1524)
				(type default)
			)
			(layer "B.SilkS")
		)
		(fp_line
			(start -2.54 -1.27)
			(end 0 -1.27)
			(stroke
				(width 0.1524)
				(type default)
			)
			(layer "B.SilkS")
		)
		(fp_poly
			(pts
				(xy 0.761746 0) (xy 2.285746 -0.762) (xy 2.285746 0.762)
			)
			(stroke
				(width 0)
				(type default)
			)
			(fill yes)
			(layer "B.SilkS")
		)
		(fp_line
			(start 0 3.81)
			(end -2.54 3.81)
			(stroke
				(width 0.1)
				(type default)
			)
			(layer "B.Fab")
		)
		(fp_line
			(start 0 -1.27)
			(end 0 3.81)
			(stroke
				(width 0.1)
				(type default)
			)
			(layer "B.Fab")
		)
		(fp_line
			(start -2.54 3.81)
			(end -2.54 -1.27)
			(stroke
				(width 0.1)
				(type default)
			)
			(layer "B.Fab")
		)
		(fp_line
			(start -2.54 -1.27)
			(end 0 -1.27)
			(stroke
				(width 0.1)
				(type default)
			)
			(layer "B.Fab")
		)
		(fp_poly
			(pts
				(xy 0.761746 0) (xy 2.285746 -0.762) (xy 2.285746 0.762)
			)
			(stroke
				(width 0)
				(type default)
			)
			(fill yes)
			(layer "B.Fab")
		)
		(pad "1" thru_hole circle
			(at 0 0)
			(size 1.0033 1.0033)
			(drill 0.249936)
			(layers "*.Cu" "*.Mask")
			(remove_unused_layers no)
			(net "TDR_DIFF_85_BOT_DIP")
			(clearance 0.10795)
			(padstack
				(mode front_inner_back)
				(layer "Inner"
					(shape circle)
					(size 0.8001 0.8001)
					(clearance 0.1524)
				)
				(layer "B.Cu"
					(shape circle)
					(size 1.0033 1.0033)
					(thermal_gap 0.10795)
					(clearance 0.10795)
				)
			)
		)
		(pad "2" thru_hole circle
			(at -2.54 0)
			(size 1.9939 1.9939)
			(drill 0.249936)
			(layers "*.Cu" "*.Mask")
			(remove_unused_layers no)
			(net "COUPON_GND1")
			(clearance 0.10795)
			(padstack
				(mode front_inner_back)
				(layer "Inner"
					(shape circle)
					(size 0.8001 0.8001)
					(clearance 0.1524)
				)
				(layer "B.Cu"
					(shape circle)
					(size 1.9939 1.9939)
					(thermal_gap 0.10795)
					(clearance 0.10795)
				)
			)
		)
		(pad "3" thru_hole circle
			(at -2.54 2.54)
			(size 1.9939 1.9939)
			(drill 0.249936)
			(layers "*.Cu" "*.Mask")
			(remove_unused_layers no)
			(net "COUPON_GND1")
			(clearance 0.10795)
			(padstack
				(mode front_inner_back)
				(layer "Inner"
					(shape circle)
					(size 0.8001 0.8001)
					(clearance 0.1524)
				)
				(layer "B.Cu"
					(shape circle)
					(size 1.9939 1.9939)
					(thermal_gap 0.10795)
					(clearance 0.10795)
				)
			)
		)
		(pad "4" thru_hole circle
			(at 0 2.54)
			(size 1.0033 1.0033)
			(drill 0.249936)
			(layers "*.Cu" "*.Mask")
			(remove_unused_layers no)
			(net "TDR_DIFF_85_BOT_DIN")
			(clearance 0.10795)
			(padstack
				(mode front_inner_back)
				(layer "Inner"
					(shape circle)
					(size 0.8001 0.8001)
					(clearance 0.1524)
				)
				(layer "B.Cu"
					(shape circle)
					(size 1.0033 1.0033)
					(thermal_gap 0.10795)
					(clearance 0.10795)
				)
			)
		)
	)
	(footprint ""
		(layer "B.Cu")
		(at 47.77486 -292.84168 90)
		(property "Reference" "C3046"
			(at 0 0 90)
			(layer "B.SilkS")
			(hide yes)
			(effects
				(font
					(size 1.27 1.27)
				)
				(justify mirror)
			)
		)
		(property "Value" ""
			(at 0 0 90)
			(layer "B.Fab")
			(effects
				(font
					(size 1.27 1.27)
				)
				(justify mirror)
			)
		)
		(duplicate_pad_numbers_are_jumpers no)
		(fp_line
			(start 0.299974 -0.150114)
			(end -0.299974 -0.150114)
			(stroke
				(width 0.1)
				(type default)
			)
			(layer "B.Fab")
		)
		(fp_line
			(start -0.299974 -0.150114)
			(end -0.299974 0.150114)
			(stroke
				(width 0.1)
				(type default)
			)
			(layer "B.Fab")
		)
		(fp_line
			(start 0.299974 0.150114)
			(end 0.299974 -0.150114)
			(stroke
				(width 0.1)
				(type default)
			)
			(layer "B.Fab")
		)
		(fp_line
			(start -0.299974 0.150114)
			(end 0.299974 0.150114)
			(stroke
				(width 0.1)
				(type default)
			)
			(layer "B.Fab")
		)
		(pad "1" smd rect
			(at 0.2667 0 270)
			(size 0.3048 0.381)
			(layers "B.Cu" "B.Mask" "B.Paste")
			(net "PCEPLL5_VDDA18_PEX0")
		)
		(pad "2" smd rect
			(at -0.2667 0 270)
			(size 0.3048 0.381)
			(layers "B.Cu" "B.Mask" "B.Paste")
			(net "GND")
		)
	)
	(footprint ""
		(layer "B.Cu")
		(at 57.749948 -299.699934 -90)
		(property "Reference" "C1234"
			(at 0 0 90)
			(layer "B.SilkS")
			(hide yes)
			(effects
				(font
					(size 1.27 1.27)
				)
				(justify mirror)
			)
		)
		(property "Value" ""
			(at 0 0 90)
			(layer "B.Fab")
			(effects
				(font
					(size 1.27 1.27)
				)
				(justify mirror)
			)
		)
		(duplicate_pad_numbers_are_jumpers no)
		(fp_line
			(start -0.299974 0.150114)
			(end 0.299974 0.150114)
			(stroke
				(width 0.1)
				(type default)
			)
			(layer "B.Fab")
		)
		(fp_line
			(start 0.299974 0.150114)
			(end 0.299974 -0.150114)
			(stroke
				(width 0.1)
				(type default)
			)
			(layer "B.Fab")
		)
		(fp_line
			(start -0.299974 -0.150114)
			(end -0.299974 0.150114)
			(stroke
				(width 0.1)
				(type default)
			)
			(layer "B.Fab")
		)
		(fp_line
			(start 0.299974 -0.150114)
			(end -0.299974 -0.150114)
			(stroke
				(width 0.1)
				(type default)
			)
			(layer "B.Fab")
		)
		(pad "1" smd rect
			(at 0.2667 0 90)
			(size 0.3048 0.381)
			(layers "B.Cu" "B.Mask" "B.Paste")
			(net "P0V8_SERDES_VDDA_PEX0")
		)
		(pad "2" smd rect
			(at -0.2667 0 90)
			(size 0.3048 0.381)
			(layers "B.Cu" "B.Mask" "B.Paste")
			(net "GND")
		)
	)
	(footprint ""
		(layer "B.Cu")
		(at 170.999912 -288.299906 90)
		(property "Reference" "C3100"
			(at 0 0 90)
			(layer "B.SilkS")
			(hide yes)
			(effects
				(font
					(size 1.27 1.27)
				)
				(justify mirror)
			)
		)
		(property "Value" ""
			(at 0 0 90)
			(layer "B.Fab")
			(effects
				(font
					(size 1.27 1.27)
				)
				(justify mirror)
			)
		)
		(duplicate_pad_numbers_are_jumpers no)
		(fp_line
			(start 0.299974 -0.150114)
			(end -0.299974 -0.150114)
			(stroke
				(width 0.1)
				(type default)
			)
			(layer "B.Fab")
		)
		(fp_line
			(start -0.299974 -0.150114)
			(end -0.299974 0.150114)
			(stroke
				(width 0.1)
				(type default)
			)
			(layer "B.Fab")
		)
		(fp_line
			(start 0.299974 0.150114)
			(end 0.299974 -0.150114)
			(stroke
				(width 0.1)
				(type default)
			)
			(layer "B.Fab")
		)
		(fp_line
			(start -0.299974 0.150114)
			(end 0.299974 0.150114)
			(stroke
				(width 0.1)
				(type default)
			)
			(layer "B.Fab")
		)
		(pad "1" smd rect
			(at 0.2667 0 270)
			(size 0.3048 0.381)
			(layers "B.Cu" "B.Mask" "B.Paste")
			(net "P1V25_PEX1")
		)
		(pad "2" smd rect
			(at -0.2667 0 270)
			(size 0.3048 0.381)
			(layers "B.Cu" "B.Mask" "B.Paste")
			(net "GND")
		)
	)
)
